%FSTAX23Y23*%
%MOIN*%
%SFA1B1*%

%IPPOS*%
%ADD17C,0.006000*%
%ADD19C,0.005000*%
%ADD22C,0.008000*%
%ADD162C,0.020000*%
%ADD172C,0.075000*%
%ADD177C,0.055000*%
%ADD181C,0.016000*%
%LNtimingcard_pcb-1*%
%LPD*%
G54D17*
X02083Y01411D02*
X02084Y01411D01*
X03407*
X03407Y01411*
G54D19*
X02589Y00324D02*
D01*
X02589Y00325*
X02589Y00325*
X02589Y00325*
X02589Y00326*
X0259Y00326*
X0259Y00326*
X0259Y00327*
X0259Y00327*
X02583Y00303D02*
D01*
X02583Y00304*
X02583Y00304*
X02583Y00304*
X02583Y00305*
X02584Y00305*
X02584Y00305*
X02577Y00297D02*
D01*
X02575Y00297*
X02574Y00297*
X02573Y00297*
X02572Y00296*
X02571Y00296*
X02569Y00295*
X02568Y00295*
X02567Y00294*
X02566Y00293*
X02565Y00292*
X02564Y00291*
X02564Y0029*
X02563Y00289*
X02562Y00288*
X02562Y00287*
X02561Y00286*
X02561Y00285*
X0256Y00283*
X0256Y00282*
X0256Y00281*
X0256Y00279*
X0256Y00278*
X0256Y00277*
X0256Y00276*
X0256Y00274*
X02561Y00273*
X02561Y00272*
X02562Y00271*
X02562Y0027*
X02563Y00269*
X02564Y00267*
X02565Y00266*
X02566Y00266*
X02567Y00265*
X02568Y00264*
X02569Y00263*
X0257Y00263*
X02571Y00262*
X02572Y00262*
X02573Y00261*
X02575Y00261*
X02576Y00261*
X02577Y00261*
X02578Y00261*
X0258Y00261*
X02581Y00261*
X02582Y00261*
X02584Y00261*
X02585Y00262*
X02586Y00262*
X02587Y00263*
X02588Y00263*
X02589Y00264*
X0259Y00265*
X02591Y00266*
X02592Y00267*
X02593Y00268*
X02594Y00269*
X02594Y0027*
X02595Y00271*
X02595Y00272*
X02596Y00274*
X02596Y00275*
X02583Y00303D02*
D01*
X02581Y00301*
X02581Y003*
X026Y00278D02*
D01*
X02599Y00278*
X02599Y00278*
X02599Y00278*
X02598Y00278*
X02598Y00277*
X02598Y00277*
X02598Y00277*
X02597Y00277*
X02597Y00276*
X02597Y00276*
X02597Y00276*
X02597Y00276*
X02596Y00275*
X02596Y00275*
X02596Y00275*
X02577Y00297D02*
D01*
X02577Y00298*
X02577Y00298*
X02578Y00298*
X02578Y00298*
X02578Y00298*
X02579Y00298*
X02579Y00298*
X02579Y00298*
X0258Y00299*
X0258Y00299*
X0258Y00299*
X0258Y00299*
X0258Y003*
X02581Y003*
X02589Y00324D02*
D01*
X02588Y00323*
X02588Y00322*
X02588Y00321*
X02587Y0032*
X02604Y00279D02*
D01*
X02603Y00279*
X02602Y00279*
X02601Y00279*
X026Y00278*
X026Y00278*
X02578Y00279D02*
D01*
X02582Y00283*
X02586Y00288*
X02589Y00292*
X02591Y00295*
X02602Y00376D02*
D01*
X02602Y00376*
X02602Y00375*
X02602Y00374*
X02602Y00374*
X02602Y00373*
X02603Y00373*
X02603Y00373*
X02603Y00372*
X02603Y00372*
X02604Y00371*
X02604Y00371*
X02604Y0037*
X02605Y0037*
X02605Y0037*
X02606Y0037*
X02606Y00369*
X02607Y00369*
X02607Y00369*
X02608Y00369*
X02608Y00369*
X02609Y00369*
X02609Y00369*
X02609Y00369*
X02616Y00354D02*
D01*
X02616Y00354*
X02617Y00354*
X02617Y00354*
X02618Y00354*
X02618Y00354*
X02619Y00354*
X02619Y00354*
X0262Y00355*
X0262Y00355*
X0262Y00355*
X02621Y00356*
X02621Y00356*
X02622Y00356*
X02622Y00357*
X02622Y00357*
X02622Y00358*
X02623Y00358*
X02623Y00359*
X02623Y00359*
X02623Y0036*
X02623Y0036*
X02623Y00361*
Y00361*
X02623Y00362*
X02623Y00362*
X02623Y00363*
X02623Y00363*
X02623Y00364*
X02622Y00364*
X02622Y00365*
X02622Y00365*
X02622Y00366*
X02621Y00366*
X02621Y00366*
X0262Y00367*
X0262Y00367*
X0262Y00367*
X02619Y00368*
X02619Y00368*
X02618Y00368*
X02618Y00368*
X02617Y00368*
X02617Y00368*
X02616Y00369*
X02616Y00369*
X02607Y00354D02*
D01*
X02607Y00354*
X02606Y00353*
X02606Y00353*
X02605Y00353*
X02604Y00353*
X02604Y00353*
X02604Y00353*
X02603Y00352*
X02603Y00352*
X02602Y00352*
X02602Y00351*
X02601Y00351*
X02601Y00351*
X02601Y0035*
X02601Y0035*
X026Y00349*
X026Y00349*
X026Y00348*
X026Y00348*
X026Y00347*
X026Y00347*
X026Y00346*
Y00346*
X026Y00345*
X026Y00345*
X026Y00344*
X026Y00344*
X026Y00343*
X026Y00343*
X02601Y00342*
X02601Y00342*
X02601Y00341*
X02601Y00341*
X02602Y00341*
X02602Y0034*
X02603Y0034*
X02603Y0034*
X02604Y00339*
X02604Y00339*
X02604Y00339*
X02605Y00339*
X02606Y00339*
X02606Y00339*
X02607Y00339*
X02607Y00339*
X02619Y00324D02*
D01*
X0262Y00324*
X0262Y00324*
X02621Y00324*
X02621Y00324*
X02622Y00324*
X02622Y00324*
X02623Y00324*
X02623Y00325*
X02624Y00325*
X02624Y00325*
X02624Y00326*
X02625Y00326*
X02625Y00326*
X02625Y00327*
X02626Y00327*
X02626Y00328*
X02626Y00328*
X02626Y00329*
X02627Y00329*
X02627Y0033*
X02627Y0033*
X02627Y00331*
Y00331*
X02627Y00332*
X02627Y00332*
X02627Y00333*
X02626Y00333*
X02626Y00334*
X02626Y00334*
X02626Y00335*
X02625Y00335*
X02625Y00336*
X02625Y00336*
X02624Y00336*
X02624Y00337*
X02624Y00337*
X02623Y00337*
X02623Y00338*
X02622Y00338*
X02622Y00338*
X02621Y00338*
X02621Y00338*
X0262Y00338*
X0262Y00339*
X02619Y00339*
X02604Y00324D02*
D01*
X02604Y00324*
X02603Y00323*
X02603Y00323*
X02602Y00323*
X02602Y00323*
X02601Y00323*
X02601Y00323*
X026Y00322*
X026Y00322*
X026Y00322*
X02599Y00321*
X02599Y00321*
X02598Y00321*
X02598Y0032*
X02598Y0032*
X02598Y00319*
X02597Y00319*
X02597Y00318*
X02597Y00318*
X02591Y00295D02*
D01*
X02591Y00295*
X02591Y00296*
X02591Y00296*
X02592Y00297*
X02592Y00297*
X02608Y00457D02*
D01*
X02604Y0045*
X026Y00444*
X02597Y00437*
X02595Y0043*
X02593Y00422*
X02591Y00415*
X0259Y00408*
X0259Y00404*
D01*
X0259Y00404*
X0259Y00404*
X02633Y00472D02*
D01*
X02628Y00467*
X02623Y00461*
X02619Y00455*
X02615Y00448*
X02612Y00442*
X02609Y00435*
X02607Y00428*
X02605Y0042*
X02603Y00413*
X02602Y00406*
X02602Y00398*
X02602Y00396*
X02625Y0048D02*
D01*
X0262Y00474*
X02616Y00469*
X02612Y00463*
X02608Y00457*
X02909Y00366D02*
D01*
X02909Y00366*
X02909Y00365*
X02909Y00365*
X02909Y00364*
X02909Y00364*
X02909Y00363*
X02909Y00363*
X0291Y00362*
X0291Y00362*
X0291Y00362*
X02911Y00361*
X02911Y00361*
X02912Y00361*
X02912Y0036*
X02912Y0036*
X02913Y0036*
X02913Y00359*
X02914Y00359*
X02914Y00359*
X02915Y00359*
X02915Y00359*
X02916Y00359*
X02916Y00359*
Y00344D02*
D01*
X02917Y00344*
X02917Y00344*
X02918Y00344*
X02918Y00344*
X02919Y00344*
X02919Y00345*
X0292Y00345*
X0292Y00345*
X02921Y00345*
X02921Y00346*
X02921Y00346*
X02922Y00346*
X02922Y00347*
X02922Y00347*
X02923Y00348*
X02923Y00348*
X02923Y00349*
X02923Y00349*
X02923Y0035*
X02924Y0035*
X02924Y00351*
X02924Y00351*
Y00352*
X02924Y00352*
X02924Y00353*
X02923Y00353*
X02923Y00354*
X02923Y00354*
X02923Y00355*
X02923Y00355*
X02922Y00356*
X02922Y00356*
X02922Y00356*
X02921Y00357*
X02921Y00357*
X02921Y00358*
X0292Y00358*
X0292Y00358*
X02919Y00358*
X02919Y00358*
X02918Y00359*
X02918Y00359*
X02917Y00359*
X02917Y00359*
X02916Y00359*
X02903Y00344D02*
D01*
X02902Y00344*
X02902Y00344*
X02901Y00344*
X02901Y00344*
X029Y00343*
X029Y00343*
X02899Y00343*
X02899Y00343*
X02898Y00343*
X02898Y00342*
X02898Y00342*
X02897Y00341*
X02897Y00341*
X02897Y00341*
X02896Y0034*
X02896Y0034*
X02896Y00339*
X02896Y00339*
X02896Y00338*
X02895Y00338*
X02895Y00337*
X02895Y00337*
Y00336*
X02895Y00336*
X02895Y00335*
X02896Y00335*
X02896Y00334*
X02896Y00334*
X02896Y00333*
X02896Y00333*
X02897Y00332*
X02897Y00332*
X02897Y00331*
X02898Y00331*
X02898Y00331*
X02898Y0033*
X02899Y0033*
X02899Y0033*
X029Y0033*
X029Y00329*
X02901Y00329*
X02901Y00329*
X02902Y00329*
X02902Y00329*
X02903Y00329*
X02915Y00314D02*
D01*
X02915Y00314*
X02916Y00314*
X02916Y00314*
X02917Y00314*
X02917Y00314*
X02918Y00315*
X02918Y00315*
X02918Y00315*
X02919Y00315*
X02919Y00316*
X0292Y00316*
X0292Y00316*
X0292Y00317*
X02921Y00317*
X02921Y00318*
X02921Y00318*
X02921Y00319*
X02922Y00319*
X02922Y0032*
X02922Y0032*
X02922Y00321*
X02922Y00321*
Y00322*
X02922Y00322*
X02922Y00323*
X02922Y00323*
X02922Y00324*
X02921Y00324*
X02921Y00325*
X02921Y00325*
X02921Y00326*
X0292Y00326*
X0292Y00326*
X0292Y00327*
X02919Y00327*
X02919Y00328*
X02918Y00328*
X02918Y00328*
X02918Y00328*
X02917Y00328*
X02917Y00329*
X02916Y00329*
X02916Y00329*
X02915Y00329*
X02915Y00329*
X02905Y00314D02*
D01*
X02904Y00314*
X02904Y00314*
X02903Y00314*
X02903Y00314*
X02902Y00313*
X02902Y00313*
X02901Y00313*
X02901Y00313*
X029Y00313*
X029Y00312*
X02899Y00312*
X02899Y00311*
X02899Y00311*
X02898Y00311*
X02898Y0031*
X02898Y0031*
X02898Y00309*
X02898Y00309*
X02897Y00308*
X02897Y00308*
X02897Y00307*
X02897Y00307*
X02897Y00306*
X02926Y004D02*
D01*
X02927Y00401*
X02927Y00401*
X02927Y00401*
X02927Y00402*
X02927Y00402*
X02927Y00402*
X02928Y00403*
X02928Y00403*
X02928Y00403*
X02928Y00404*
X02928Y00404*
X02928Y00404*
X02885Y00274D02*
D01*
X02886Y00273*
X02886Y00272*
X02887Y00271*
X02888Y00269*
X02888Y00268*
X02889Y00267*
X0289Y00266*
X02891Y00265*
X02892Y00264*
X02893Y00263*
X02894Y00263*
X02895Y00262*
X02896Y00261*
X02898Y00261*
X02899Y00261*
X029Y0026*
X02902Y0026*
X02903Y0026*
X02904Y0026*
X02906Y0026*
X02907Y0026*
X02908Y0026*
X0291Y00261*
X02911Y00261*
X02912Y00262*
X02913Y00262*
X02915Y00263*
X02916Y00264*
X02917Y00264*
X02918Y00265*
X02919Y00266*
X02919Y00267*
X0292Y00268*
X02921Y0027*
X02922Y00271*
X02922Y00272*
X02923Y00273*
X02923Y00275*
X02923Y00275*
X02911Y004D02*
D01*
X02911Y004*
X02911Y004*
X02911Y00401*
X02912Y00401*
X02912Y00401*
X02912Y00401*
X02912Y00402*
X02911Y004D02*
D01*
X02907Y00397*
X02904Y00395*
X02901Y00392*
X02899Y00389*
X02896Y00386*
X02894Y00382*
X02892Y00379*
X0289Y00375*
X02889Y00372*
X02888Y00368*
X02887Y00364*
X02886Y0036*
X02885Y00356*
X02885Y00352*
X02912Y00402D02*
D01*
X02913Y00404*
X02914Y00406*
X02915Y00408*
X02916Y0041*
X02916Y00413*
X02917Y00415*
X02917Y00418*
X02917Y00419*
X02928Y00834D02*
D01*
X02928Y00835*
X02928Y00836*
X02928Y00836*
X02927Y00837*
X02927Y00838*
X02927Y00839*
X02927Y00839*
X02926Y0084*
X02926Y00841*
X02925Y00841*
X02925Y00842*
X02925Y00842*
X02897Y00289D02*
D01*
X02897Y00289*
X02897Y00288*
X02897Y00288*
X02897Y00288*
X02897Y00287*
X02898Y00287*
X02898Y00287*
X02898Y00286*
X02898Y00286*
X02898Y00286*
X02899Y00285*
X02899Y00285*
X02759Y0094D02*
D01*
X02759Y00938*
X02759Y00935*
X0276Y00933*
X0276Y0093*
X02761Y00928*
X02762Y00925*
X02763Y00923*
X02765Y00921*
X02766Y00919*
X02768Y00917*
X02769Y00915*
X0277Y00914*
X02767Y00976D02*
D01*
X02766Y00974*
X02765Y00973*
X02764Y00971*
X02762Y00969*
X02762Y00968*
X02761Y00966*
X0276Y00964*
X0276Y00962*
X02759Y0096*
X02759Y00958*
X02759Y00956*
X02759Y00956*
X02915Y00852D02*
D01*
X02912Y00854*
X0291Y00856*
X02907Y00858*
X02904Y0086*
X02901Y00861*
X02898Y00863*
X02895Y00864*
X02892Y00864*
X02889Y00865*
X02886Y00865*
X02882Y00866*
X02881Y00866*
X02789Y00895D02*
D01*
X02794Y0089*
X028Y00886*
X02805Y00882*
X02811Y00878*
X02818Y00875*
X02824Y00872*
X02831Y0087*
X02837Y00868*
X02844Y00867*
X02851Y00866*
X02858Y00866*
X0286Y00866*
X02748Y00285D02*
D01*
X02748Y00284*
X02748Y00284*
X02748Y00283*
X02748Y00283*
X02748Y00283*
X02748Y00282*
X02748Y00282*
X02748Y00282*
X02748Y00282*
X02737Y00267D02*
D01*
X02738Y00266*
X02739Y00265*
X0274Y00265*
X02741Y00264*
X02742Y00263*
X02743Y00263*
X02744Y00263*
X02745Y00262*
X02746Y00262*
X02747Y00262*
X02749Y00262*
X0275Y00262*
X02751Y00262*
X02752Y00262*
X02753Y00262*
X02754Y00263*
X02755Y00263*
X02757Y00264*
X02758Y00264*
X02759Y00265*
X0276Y00265*
X0276Y00266*
X02761Y00267*
X02762Y00268*
X02763Y00269*
X02763Y0027*
X02764Y00271*
X02765Y00272*
X02765Y00273*
X02765Y00274*
X02766Y00275*
X02737Y00387D02*
D01*
X02733Y00383*
X0273Y00378*
X02726Y00373*
X02723Y00368*
X0272Y00363*
X02718Y00357*
X02716Y00352*
X02715Y00346*
X02714Y0034*
X02713Y00334*
X02713Y00329*
X02713Y00327*
D01*
X02713Y00321*
X02713Y00315*
X02714Y00309*
X02716Y00303*
X02718Y00297*
X0272Y00292*
X02723Y00286*
X02726Y00281*
X02729Y00276*
X02733Y00271*
X02737Y00267*
X02737Y00267*
X0274Y00348D02*
D01*
X02741Y00348*
X02741Y00348*
X02742Y00348*
X02742Y00348*
X02743Y00348*
X02743Y00348*
X02744Y00348*
X02744Y00349*
X02744Y00349*
X02745Y00349*
X02745Y0035*
X02746Y0035*
X02746Y00351*
X02746Y00351*
X02747Y00351*
X02747Y00352*
X02747Y00352*
X02747Y00353*
X02747Y00353*
X02747Y00354*
X02748Y00354*
X02748Y00355*
X02748Y00355*
X02733Y00348D02*
D01*
X02733Y00348*
X02732Y00348*
X02732Y00347*
X02731Y00347*
X02731Y00347*
X0273Y00347*
X0273Y00347*
X02729Y00346*
X02729Y00346*
X02729Y00346*
X02728Y00346*
X02728Y00345*
X02728Y00345*
X02727Y00344*
X02727Y00344*
X02727Y00343*
X02726Y00343*
X02726Y00342*
X02726Y00342*
X02726Y00341*
X02726Y00341*
X02726Y0034*
Y0034*
X02726Y00339*
X02726Y00339*
X02726Y00338*
X02726Y00338*
X02726Y00337*
X02727Y00337*
X02727Y00336*
X02727Y00336*
X02728Y00336*
X02728Y00335*
X02728Y00335*
X02729Y00334*
X02729Y00334*
X02729Y00334*
X0273Y00333*
X0273Y00333*
X02731Y00333*
X02731Y00333*
X02732Y00333*
X02732Y00333*
X02733Y00333*
X02733Y00333*
X0275Y00318D02*
D01*
X02751Y00318*
X02751Y00318*
X02752Y00318*
X02752Y00318*
X02753Y00318*
X02753Y00318*
X02754Y00318*
X02754Y00319*
X02754Y00319*
X02755Y00319*
X02755Y0032*
X02756Y0032*
X02756Y00321*
X02756Y00321*
X02757Y00321*
X02757Y00322*
X02757Y00322*
X02757Y00323*
X02757Y00323*
X02757Y00324*
X02758Y00324*
X02758Y00325*
Y00325*
X02758Y00326*
X02757Y00326*
X02757Y00327*
X02757Y00327*
X02757Y00328*
X02757Y00328*
X02757Y00329*
X02756Y00329*
X02756Y0033*
X02756Y0033*
X02755Y00331*
X02755Y00331*
X02754Y00331*
X02754Y00331*
X02754Y00332*
X02753Y00332*
X02753Y00332*
X02752Y00332*
X02752Y00332*
X02751Y00333*
X02751Y00333*
X0275Y00333*
X02733Y00318D02*
D01*
X02733Y00318*
X02732Y00318*
X02732Y00317*
X02731Y00317*
X02731Y00317*
X0273Y00317*
X0273Y00317*
X02729Y00316*
X02729Y00316*
X02729Y00316*
X02728Y00316*
X02728Y00315*
X02728Y00315*
X02727Y00314*
X02727Y00314*
X02727Y00313*
X02726Y00313*
X02726Y00312*
X02726Y00312*
X02726Y00311*
X02726Y00311*
X02726Y0031*
Y0031*
X02726Y00309*
X02726Y00309*
X02726Y00308*
X02726Y00308*
X02726Y00307*
X02727Y00307*
X02727Y00306*
X02727Y00306*
X02728Y00306*
X02728Y00305*
X02728Y00305*
X02729Y00304*
X02729Y00304*
X02729Y00304*
X0273Y00303*
X0273Y00303*
X02731Y00303*
X02731Y00303*
X02732Y00303*
X02732Y00303*
X02733Y00303*
X02733Y00303*
X02748Y00295D02*
D01*
X02748Y00296*
X02747Y00296*
X02747Y00297*
X02747Y00297*
X02747Y00298*
X02747Y00298*
X02747Y00299*
X02746Y00299*
X02746Y003*
X02746Y003*
X02745Y003*
X02745Y00301*
X02745Y00301*
X02744Y00301*
X02744Y00302*
X02743Y00302*
X02743Y00302*
X02742Y00302*
X02742Y00302*
X02741Y00302*
X02741Y00303*
X0274Y00303*
X0274Y00303*
X02749Y00383D02*
D01*
X02749Y00383*
X02749Y00383*
X02748Y00382*
X02748Y00382*
X02748Y00382*
X02748Y00381*
X02748Y00381*
X02748Y00381*
X02748Y0038*
X02748Y0038*
X02748Y0038*
X02748Y0038*
X02515Y0036D02*
D01*
X02515Y0036*
X02516Y00359*
X02516Y00359*
X02517Y00359*
X02517Y00359*
X02518Y00358*
X02518Y00358*
X02519Y00358*
X02519Y00358*
X0252Y00358*
X0252Y00358*
X02521Y00358*
X02521Y00358*
X02522Y00358*
X02522Y00358*
X02523Y00358*
X02523Y00359*
X02524Y00359*
X02524Y00359*
X02525Y00359*
X02525Y0036*
X02525Y0036*
X02526Y0036*
X02515D02*
D01*
X02515Y00361*
X02514Y00361*
X02514Y00361*
X02513Y00361*
X02513Y00362*
X02512Y00362*
X02512Y00362*
X02511Y00362*
X02511Y00362*
X0251Y00362*
X0251Y00362*
X02509Y00362*
X02509Y00362*
X02508Y00362*
X02508Y00362*
X02507Y00362*
X02507Y00362*
X02506Y00362*
X02506Y00361*
X02505Y00361*
X02505Y00361*
X02505Y0036*
X02504Y0036*
D01*
X02504Y0036*
X02504Y00359*
X02503Y00359*
X02503Y00359*
X02503Y00358*
X02503Y00358*
X02502Y00357*
X02502Y00357*
X02502Y00356*
X02502Y00356*
X02502Y00355*
X02502Y00354*
X02502Y00354*
X02502Y00353*
X02502Y00353*
X02503Y00352*
X02503Y00352*
X02503Y00351*
X02503Y00351*
X02503Y00351*
X02504Y0035*
X02504Y0035*
X02504Y0035*
Y00339D02*
D01*
X02505Y00339*
X02505Y0034*
X02505Y0034*
X02506Y00341*
X02506Y00341*
X02506Y00342*
X02506Y00342*
X02506Y00343*
X02506Y00343*
X02506Y00344*
X02507Y00344*
X02507Y00345*
X02506Y00345*
X02506Y00346*
X02506Y00346*
X02506Y00347*
X02506Y00347*
X02506Y00348*
X02505Y00348*
X02505Y00349*
X02505Y00349*
X02505Y00349*
X02504Y0035*
X02494Y00339D02*
D01*
X02494Y00339*
X02495Y00338*
X02495Y00338*
X02495Y00338*
X02496Y00337*
X02496Y00337*
X02497Y00337*
X02497Y00337*
X02498Y00337*
X02498Y00337*
X02499Y00337*
X02499Y00337*
X025Y00337*
X025Y00337*
X02501Y00337*
X02501Y00337*
X02502Y00337*
X02502Y00338*
X02503Y00338*
X02503Y00338*
X02504Y00338*
X02504Y00339*
X02504Y00339*
X02491Y00341D02*
D01*
X02491Y00342*
X0249Y00342*
X0249Y00342*
X0249Y00343*
X02489Y00343*
X02489Y00343*
X02488Y00343*
X02488Y00343*
X02487Y00344*
X02487Y00344*
X02486Y00344*
X02486Y00344*
X02485Y00344*
X02485Y00343*
X02484Y00343*
X02484Y00343*
X02483Y00343*
X02483Y00343*
X02482Y00343*
X02482Y00342*
X02481Y00342*
X02481Y00342*
X02481Y00341*
D01*
X0248Y00341*
X0248Y00341*
X0248Y0034*
X02479Y0034*
X02479Y00339*
X02479Y00339*
X02479Y00338*
X02479Y00338*
X02479Y00337*
X02478Y00337*
X02478Y00336*
X02478Y00336*
X02479Y00335*
X02479Y00335*
X02479Y00334*
X02479Y00334*
X02479Y00333*
X02479Y00333*
X0248Y00332*
X0248Y00332*
X0248Y00331*
X0248Y00331*
X02481Y00331*
X02483Y00318D02*
D01*
X02483Y00318*
X02484Y00319*
X02484Y00319*
X02484Y00319*
X02485Y0032*
X02485Y0032*
X02485Y00321*
X02485Y00321*
X02485Y00322*
X02485Y00322*
X02485Y00323*
X02485Y00323*
X02485Y00324*
X02485Y00324*
X02485Y00325*
X02485Y00326*
X02485Y00326*
X02484Y00326*
X02484Y00327*
X02484Y00327*
X02484Y00328*
X02483Y00328*
X02483Y00328*
X02473Y00318D02*
D01*
X02473Y00317*
X02473Y00317*
X02474Y00317*
X02474Y00317*
X02475Y00316*
X02475Y00316*
X02476Y00316*
X02476Y00316*
X02477Y00316*
X02477Y00316*
X02478Y00316*
X02478Y00316*
X02479Y00316*
X02479Y00316*
X0248Y00316*
X0248Y00316*
X02481Y00316*
X02481Y00316*
X02482Y00317*
X02482Y00317*
X02483Y00317*
X02483Y00318*
X02483Y00318*
X02469Y00321D02*
D01*
X02469Y00321*
X02468Y00322*
X02468Y00322*
X02468Y00322*
X02467Y00323*
X02467Y00323*
X02466Y00323*
X02466Y00323*
X02465Y00323*
X02465Y00323*
X02464Y00323*
X02464Y00323*
X02463Y00323*
X02462Y00323*
X02462Y00323*
X02461Y00323*
X02461Y00323*
X02461Y00322*
X0246Y00322*
X0246Y00322*
X02459Y00322*
X02459Y00321*
X02459Y00321*
D01*
X02458Y00321*
X02458Y0032*
X02458Y0032*
X02457Y00319*
X02457Y00319*
X02457Y00318*
X02457Y00318*
X02457Y00317*
X02456Y00317*
X02456Y00316*
X02456Y00316*
X02456Y00315*
X02456Y00315*
X02457Y00314*
X02457Y00314*
X02457Y00313*
X02457Y00313*
X02457Y00312*
X02457Y00312*
X02458Y00311*
X02458Y00311*
X02458Y00311*
X02459Y0031*
X02462Y00297D02*
D01*
X02462Y00297*
X02463Y00297*
X02463Y00298*
X02463Y00298*
X02463Y00299*
X02464Y00299*
X02464Y003*
X02464Y003*
X02464Y00301*
X02464Y00301*
X02464Y00302*
X02464Y00302*
X02464Y00303*
X02464Y00303*
X02464Y00304*
X02464Y00304*
X02463Y00305*
X02463Y00305*
X02463Y00306*
X02463Y00306*
X02462Y00307*
X02462Y00307*
X02462Y00307*
X02885Y00276D02*
D01*
X02885Y00275*
X02885Y00275*
X02885Y00275*
X02885Y00274*
X02928Y00279D02*
D01*
X02928Y00279*
X02927Y00279*
X02927Y00279*
X02927Y00279*
X02926Y00279*
X02926Y00279*
X02926Y00278*
X02925Y00278*
X02925Y00278*
X02925Y00278*
X02925Y00278*
X02924Y00277*
X02924Y00277*
X02924Y00277*
X02924Y00277*
X02923Y00276*
X02923Y00276*
X02923Y00276*
X02923Y00275*
X02923Y00275*
X02771Y00279D02*
D01*
X0277Y00279*
X0277Y00279*
X02769Y00279*
X02769Y00279*
X02769Y00279*
X02768Y00279*
X02768Y00278*
X02768Y00278*
X02768Y00278*
X02767Y00278*
X02767Y00278*
X02767Y00277*
X02767Y00277*
X02766Y00277*
X02766Y00277*
X02766Y00276*
X02766Y00276*
X02766Y00276*
X02766Y00275*
X02766Y00275*
X02692Y00795D02*
D01*
X02691Y00793*
X0269Y00792*
X02689Y0079*
X02688Y00788*
X02687Y00787*
X02686Y00785*
X02685Y00783*
X02685Y00781*
X02684Y00779*
X02684Y00777*
X02684Y00775*
X02684Y00775*
X02652Y0049D02*
D01*
X02657Y00496*
X02662Y00502*
X02666Y00508*
X0267Y00515*
X02674Y00522*
X02677Y00529*
X02679Y00536*
X02681Y00544*
X02683Y00551*
X02684Y00559*
X02684Y00567*
X02684Y00569*
X02673Y00775D02*
D01*
X02673Y00777*
X02673Y00779*
X02673Y00781*
X02672Y00782*
X02671Y00784*
X02671Y00786*
X0267Y00788*
X02669Y0079*
X02668Y00791*
X02667Y00793*
X02665Y00794*
X02665Y00795*
X02644Y00498D02*
D01*
X02649Y00503*
X02653Y00509*
X02657Y00514*
X02661Y0052*
X02664Y00527*
X02666Y00533*
X02669Y0054*
X02671Y00546*
X02672Y00553*
X02673Y0056*
X02673Y00567*
X02673Y00569*
X02563Y00383D02*
D01*
X02563Y00384*
X02564Y00385*
X02565Y00385*
X02565Y00386*
X02565Y00387*
X02566Y00388*
X02566Y00389*
X02566Y00389*
X02566Y0039*
X02566Y0039*
X02464Y00285D02*
D01*
X02464Y00284*
X02464Y00284*
X02464Y00284*
X02463Y00284*
X02463Y00283*
X02463Y00283*
X02463Y00283*
X02463Y00282*
X02463Y00282*
X02463Y00282*
X02463Y00281*
X02463Y00281*
X02463Y00281*
X02578Y0083D02*
D01*
X02576Y00828*
X02574Y00826*
X02573Y00824*
X02571Y00821*
X0257Y00819*
X02569Y00816*
X02568Y00814*
X02567Y00811*
X02567Y00808*
X02567Y00806*
X02566Y00803*
X02566Y00802*
X02807Y00775D02*
D01*
X02807Y00777*
X02807Y00779*
X02806Y00781*
X02806Y00782*
X02805Y00784*
X02805Y00786*
X02804Y00788*
X02803Y0079*
X02802Y00791*
X028Y00793*
X02799Y00794*
X02799Y00795*
X02795Y00429D02*
D01*
X02798Y00433*
X02802Y00437*
X02805Y00442*
X02808Y00446*
X02811Y00451*
X02813Y00456*
X02815Y00462*
X02816Y00467*
X02817Y00473*
X02818Y00478*
X02818Y00484*
X02818Y00485*
X02826Y00795D02*
D01*
X02825Y00793*
X02824Y00792*
X02823Y0079*
X02822Y00788*
X02821Y00787*
X0282Y00785*
X02819Y00783*
X02819Y00781*
X02818Y00779*
X02818Y00777*
X02818Y00775*
X02818Y00775*
X02787Y00437D02*
D01*
X0279Y0044*
X02793Y00444*
X02796Y00448*
X02798Y00452*
X02801Y00456*
X02802Y0046*
X02804Y00465*
X02805Y0047*
X02806Y00474*
X02807Y00479*
X02807Y00484*
X02807Y00485*
X02426Y00275D02*
D01*
X02427Y00274*
X02427Y00273*
X02428Y00271*
X02428Y0027*
X02429Y00269*
X02429Y00268*
X0243Y00267*
X02431Y00266*
X02432Y00265*
X02433Y00264*
X02434Y00264*
X02435Y00263*
X02436Y00262*
X02438Y00262*
X02439Y00261*
X0244Y00261*
X02441Y00261*
X02443Y00261*
X02444Y00261*
X02445Y00261*
X02446Y00261*
X02448Y00261*
X02449Y00261*
X0245Y00261*
X02451Y00262*
X02453Y00262*
X02454Y00263*
X02455Y00264*
X02456Y00265*
X02457Y00265*
X02458Y00266*
X02459Y00267*
X02459Y00268*
X0246Y00269*
X02461Y0027*
X02461Y00272*
X02462Y00273*
X02462Y00274*
X02463Y00275*
X02463Y00277*
X02463Y00278*
X02463Y00279*
X02463Y0028*
X02463Y00281*
X02553Y00388D02*
D01*
X02554Y00388*
X02554Y00389*
X02554Y00389*
X02554Y0039*
X02555Y0039*
X02555Y00391*
X02555Y00391*
X02555Y00392*
X02555Y00392*
X02555Y00393*
X02555Y00393*
Y00393*
X0257Y00838D02*
D01*
X02568Y00835*
X02566Y00833*
X02564Y0083*
X02562Y00827*
X0256Y00824*
X02559Y0082*
X02558Y00817*
X02557Y00814*
X02556Y0081*
X02556Y00806*
X02555Y00803*
X02555Y00802*
X02917Y0082D02*
D01*
X02917Y00822*
X02916Y00825*
X02916Y00827*
X02916Y00829*
X02915Y00832*
X02914Y00834*
X02913Y00836*
X02912Y00838*
X0291Y0084*
X02909Y00842*
X02907Y00844*
X02907Y00844*
D01*
X02905Y00846*
X02903Y00847*
X02901Y00849*
X02899Y0085*
X02897Y00851*
X02894Y00852*
X02892Y00853*
X0289Y00854*
X02887Y00854*
X02885Y00855*
X02882Y00855*
X02881Y00855*
X02781Y00887D02*
D01*
X02787Y00882*
X02793Y00877*
X02799Y00873*
X02806Y00869*
X02813Y00865*
X0282Y00862*
X02827Y00859*
X02835Y00857*
X02842Y00856*
X0285Y00855*
X02858Y00855*
X0286Y00855*
X02748Y0094D02*
D01*
X02748Y00937*
X02748Y00934*
X02749Y0093*
X0275Y00927*
X02751Y00924*
X02752Y00921*
X02754Y00918*
X02755Y00915*
X02757Y00912*
X02759Y0091*
X02761Y00907*
X02762Y00907*
X02748Y00956D02*
D01*
X02748Y00958*
X02748Y0096*
X02747Y00962*
X02747Y00964*
X02746Y00965*
X02745Y00967*
X02745Y00969*
X02744Y00971*
X02743Y00972*
X02741Y00974*
X0274Y00975*
X0274Y00976*
X02426Y00275D02*
D01*
X02426Y00275*
X02426Y00276*
X02426Y00276*
X02426Y00276*
X02426Y00277*
X02425Y00277*
X02425Y00277*
X02425Y00278*
X02425Y00278*
X02424Y00278*
X02424Y00278*
X02424Y00278*
X02424Y00279*
X02423Y00279*
X02423Y00279*
X02423Y00279*
X02422Y00279*
X02422Y00279*
X02422Y00279*
X02421Y00279*
X02608Y00861D02*
D01*
X02614Y00866*
X02618Y00872*
X02623Y00879*
X02627Y00885*
X0263Y00892*
X02633Y00899*
X02636Y00907*
X02638Y00914*
X02639Y00922*
X0264Y00929*
X02641Y00937*
X02641Y00939*
X02649Y00976D02*
D01*
X02648Y00974*
X02647Y00973*
X02645Y00971*
X02644Y00969*
X02643Y00968*
X02643Y00966*
X02642Y00964*
X02642Y00962*
X02641Y0096*
X02641Y00958*
X02641Y00956*
X02641Y00956*
X02601Y00868D02*
D01*
X02605Y00873*
X0261Y00879*
X02614Y00884*
X02617Y0089*
X0262Y00897*
X02623Y00903*
X02625Y0091*
X02627Y00916*
X02629Y00923*
X02629Y0093*
X0263Y00937*
X0263Y00939*
Y00956D02*
D01*
X0263Y00958*
X0263Y0096*
X02629Y00962*
X02629Y00964*
X02628Y00965*
X02627Y00967*
X02627Y00969*
X02626Y00971*
X02624Y00972*
X02623Y00974*
X02622Y00975*
X02622Y00976*
X02584Y00305D02*
X02587Y0032D01*
X02577Y00297D02*
D01*
X0259Y00327D02*
Y00404D01*
X02596Y00275D02*
X02596Y00275D01*
X02604Y00279D02*
X0261D01*
X026Y00278D02*
D01*
X02602Y00389D02*
D01*
Y00387D02*
Y00389D01*
Y00376D02*
Y00387D01*
X02609Y00369D02*
X02616D01*
X02607Y00354D02*
X02616D01*
X02607Y00339D02*
X02619D01*
X02604Y00324D02*
X02619D01*
X02597Y00318D02*
D01*
X02592Y00297D02*
X02597Y00318D01*
X02602Y00389D02*
Y00396D01*
X0259Y00404D02*
D01*
X02608Y00457D02*
D01*
X02923Y00398D02*
X02926Y004D01*
X0291Y00384D02*
X02923Y00398D01*
X02909Y00381D02*
X0291Y00384D01*
X02909Y00366D02*
Y00381D01*
X02916Y00359D02*
D01*
X02903Y00344D02*
X02916D01*
X02903Y00329D02*
X02915D01*
X02905Y00314D02*
X02915D01*
X02897Y00291D02*
Y00306D01*
Y00291D02*
Y00289D01*
X02926Y004D02*
X02926Y004D01*
X02928Y00404D02*
Y00834D01*
X02923Y00275D02*
D01*
X02911Y004D02*
X02911Y004D01*
X02912Y00402D02*
D01*
X02917Y00419D02*
Y0082D01*
Y00419D02*
Y00419D01*
X02915Y00852D02*
X02925Y00842D01*
X02899Y00285D02*
D01*
X02767Y00976D02*
Y00976D01*
X02759Y0094D02*
Y00956D01*
X0277Y00914D02*
X02789Y00895D01*
X0286Y00866D02*
X02881D01*
X02899Y00285D02*
X02905Y00279D01*
X02885Y00352D02*
Y00352D01*
Y00276D02*
Y00352D01*
X02748Y00282D02*
D01*
X02748Y00285D02*
D01*
X02737Y00267D02*
X02737Y00267D01*
X02748Y00285D02*
Y00289D01*
X02737Y00387D02*
X02787Y00437D01*
X02748Y00377D02*
Y0038D01*
X02748Y00355D02*
X02748Y00377D01*
X02748Y00355D02*
D01*
X02733Y00348D02*
X0274D01*
X02733Y00333D02*
X0275D01*
X02733Y00318D02*
X0275D01*
X02733Y00303D02*
X0274D01*
X02748Y00295D02*
D01*
Y00291D02*
Y00295D01*
X02748Y00289D02*
X02748Y00291D01*
X02748Y0038D02*
D01*
X02749Y00383D02*
X02795Y00429D01*
X02633Y00472D02*
X02652Y0049D01*
X02633Y00472D02*
D01*
X02526Y0036D02*
X02543Y00378D01*
X02515Y0036D02*
D01*
D01*
X02504Y0035D02*
D01*
X02491Y00341D02*
X02494Y00339D01*
X02481Y00331D02*
X02483Y00328D01*
X02469Y00321D02*
X02473Y00318D01*
X02459Y0031D02*
X02462Y00307D01*
X0246Y00295D02*
X02462Y00297D01*
X02543Y00378D02*
X02553Y00388D01*
X02444Y00279D02*
X0246Y00295D01*
X02807Y00485D02*
Y00775D01*
X02818Y00485D02*
Y00775D01*
X02673Y00569D02*
Y00775D01*
X02684Y00569D02*
Y00775D01*
X02555Y00393D02*
Y00802D01*
X02692Y00795D02*
Y00795D01*
X02665Y00795D02*
Y00795D01*
X02625Y0048D02*
X02644Y00498D01*
X02464Y00285D02*
X02563Y00383D01*
X02566Y0039D02*
Y00802D01*
X02771Y00279D02*
X02779D01*
X02799Y00795D02*
Y00795D01*
X02826Y00795D02*
Y00795D01*
X02578Y0083D02*
X02608Y00861D01*
X02463Y00281D02*
D01*
X02578Y0083D02*
D01*
X02555Y00393D02*
D01*
X02928Y00279D02*
X02937D01*
X02881Y00855D02*
D01*
X0286D02*
X02881D01*
X02748Y0094D02*
Y00956D01*
X0274Y00976D02*
Y00976D01*
X02762Y00907D02*
X02781Y00887D01*
X02421Y00279D02*
D01*
X02413D02*
X02421D01*
X02641Y00939D02*
Y00956D01*
X02649Y00976D02*
Y00976D01*
Y00976D02*
D01*
X0257Y00838D02*
X02601Y00868D01*
X0263Y00939D02*
Y00956D01*
X02622Y00976D02*
Y00976D01*
G54D22*
X02926Y02478D02*
D01*
X02925Y02479*
X02925Y02479*
X02924Y02479*
X02924Y0248*
X02923Y0248*
X02923Y0248*
X02922Y0248*
X02922Y0248*
X02921Y0248*
X02921Y02481*
X0292Y02481*
X0292Y02481*
X02626Y02716D02*
D01*
X02627Y02716*
X02627Y02716*
X02628Y02716*
X02628Y02716*
X02629Y02717*
X02629Y02717*
X0263Y02717*
X0263Y02717*
X02631Y02718*
X02631Y02718*
X02632Y02718*
X02632Y02718*
X02671Y02754D02*
D01*
X02671Y02754*
X0267Y02754*
X02669Y02754*
X02669Y02754*
X02668Y02754*
X02668Y02754*
X02667Y02753*
X02667Y02753*
X02666Y02753*
X02666Y02753*
X02666Y02752*
X02665Y02752*
X02396Y02718D02*
D01*
X02396Y02718*
X02397Y02718*
X02397Y02717*
X02398Y02717*
X02398Y02717*
X02399Y02717*
X02399Y02716*
X024Y02716*
X024Y02716*
X02401Y02716*
X02401Y02716*
X02401Y02716*
X02629Y02272D02*
X0263Y02271D01*
X02644*
X02645Y0227*
X02586Y02406D02*
X04039D01*
X0258Y02412D02*
X02586Y02406D01*
X02575Y02412D02*
X0258D01*
X03409Y02889D02*
X0341Y0289D01*
X03413*
X03351Y02889D02*
X03409D01*
X03413Y0289D02*
X03414Y02892D01*
X03277Y02963D02*
X03351Y02889D01*
X04208Y03661D02*
X04385D01*
X03657Y03296D02*
X03658Y03296D01*
X06433*
X03745Y01679D02*
X03747D01*
X03732Y01693D02*
X03745Y01679D01*
X0361Y01693D02*
X03732D01*
X03599Y01682D02*
X0361Y01693D01*
X03429Y0168D02*
X03431Y01682D01*
X03599*
X03782Y01641D02*
X03792Y01651D01*
X02666Y0164D02*
X02667Y01641D01*
X03782*
X03358Y03472D02*
X03409Y03523D01*
X0407*
X04078Y03366D02*
X0409Y03354D01*
X04438*
X03732Y03366D02*
X04078D01*
X05031Y03371D02*
X06409D01*
X03647Y03379D02*
X05023D01*
X0362Y03351D02*
X03647Y03379D01*
X03704Y03338D02*
X03732Y03366D01*
X05023Y03379D02*
X05031Y03371D01*
X03491Y03297D02*
X03533Y03338D01*
X03458Y03344D02*
X03466Y03351D01*
X0362*
X03542Y03318D02*
X03543Y03319D01*
X03302Y03344D02*
X03458D01*
X03533Y03338D02*
X03704D01*
X03543Y03319D02*
X06342D01*
X06354Y03331*
X03437Y03476D02*
X03437Y03475D01*
Y03456D02*
Y03475D01*
Y03456D02*
X03457Y03436D01*
X04926Y034D02*
X04927Y03401D01*
X03394Y03447D02*
X03441Y034D01*
X06445Y03396D02*
X06447D01*
X03441Y034D02*
X04926D01*
X03457Y03436D02*
X06469D01*
X04927Y03401D02*
X0644D01*
X06445Y03396*
X06469Y03436D02*
X06479Y03426D01*
X03469Y03456D02*
X06509D01*
X03358Y03448D02*
X03358Y03448D01*
X03358Y03448D02*
Y03472D01*
X0407Y03523D02*
X04208Y03661D01*
X02841Y02263D02*
X03342D01*
X00862Y01216D02*
X00901Y01177D01*
X01003*
X00862Y01216D02*
Y021D01*
X00997Y02236*
X03197Y01685D02*
X03205Y01694D01*
X01885Y01665D02*
X03195D01*
X01893Y01685D02*
X03197D01*
X02576Y01705D02*
X02604Y01734D01*
X03195Y01665D02*
X03211Y01681D01*
X01822Y01674D02*
X01877D01*
X01015Y01705D02*
X02576D01*
X01877Y01674D02*
X01885Y01665D01*
X038Y032D02*
X0628D01*
X03799Y03201D02*
X038Y032D01*
X03504Y04086D02*
X03505Y04086D01*
X0522D02*
X0522Y04086D01*
X03505Y04086D02*
X0522D01*
X06333Y03155D02*
X06334Y03154D01*
Y03148D02*
Y03154D01*
X06285Y03195D02*
X06287D01*
X06247Y03235D02*
X06262Y0322D01*
X06334Y03148D02*
X06335Y03147D01*
X0628Y032D02*
X06285Y03195D01*
X03806Y03235D02*
X06247D01*
X02926Y02478D02*
X02948Y02456D01*
X02616Y02481D02*
X0292D01*
D01*
X02671Y02754D02*
X03089D01*
X02401Y02716D02*
X02626D01*
X02671Y02754D02*
X02671D01*
X02632Y02718D02*
X02665Y02752D01*
X02394Y0272D02*
X02396Y02718D01*
X02494Y02661D02*
X04114D01*
X0233Y02215D02*
X05577D01*
X01393Y01816D02*
X01517Y01941D01*
X02384*
X01399Y03522D02*
X014Y03523D01*
X01408Y03979D02*
Y0398D01*
X014Y03971D02*
X01408Y03979D01*
X014Y03523D02*
Y03971D01*
X01399Y03075D02*
Y03522D01*
X04605Y02997D02*
X04794Y02808D01*
X03276Y02964D02*
X03277Y02963D01*
X03276Y02964D02*
Y02983D01*
X03275Y02984D02*
X03276Y02983D01*
X03275Y02984D02*
Y03019D01*
X03331Y03075*
Y03153*
X03297Y03187D02*
X03331Y03153D01*
X0321Y03135D02*
X03262Y03187D01*
X03297*
X03183Y03135D02*
X0321D01*
X03232Y03187D02*
X0326Y03215D01*
X03468*
X03188Y03187D02*
X03232D01*
X01798Y01304D02*
X0181Y01316D01*
X02189Y01281D02*
X02206Y01298D01*
X01572Y01281D02*
X02189D01*
X01567Y01285D02*
X01572Y01281D01*
X0406Y03155D02*
D01*
X03854Y03151D02*
X03857D01*
X03861Y03155*
X0406*
X04012Y03115D02*
D01*
X03939Y03121D02*
X03942D01*
X03948Y03115*
X04012*
X06296D01*
X03232Y03098D02*
X03275Y03141D01*
X03089Y02754D02*
X03232Y02897D01*
Y03098*
X03097Y0297D02*
X03197D01*
X03096Y02969D02*
X03097Y0297D01*
X02577Y02969D02*
X03096D01*
X05049Y03264D02*
X0505Y03266D01*
X03744Y03261D02*
X03747D01*
X0375Y03264*
X05049*
X03687Y02997D02*
X04605D01*
X03468Y03215D02*
X03687Y02997D01*
X02997Y03235D02*
X0323D01*
X02362Y02696D02*
X02494D01*
X02509Y02681*
X02217Y0284D02*
X02362Y02696D01*
X01399Y03075D02*
X01634Y0284D01*
X02217*
X01879Y01811D02*
X03056D01*
X02635Y0179D02*
X02646Y01779D01*
X02579Y0179D02*
X02635D01*
X02385Y032D02*
X02411Y03174D01*
X01459Y03147D02*
X02435D01*
X02205Y032D02*
X02385D01*
X02435Y03147D02*
X0246Y03172D01*
X02405Y03261D02*
X02411Y03266D01*
X02259Y03261D02*
X02405D01*
X03366Y0327D02*
X03367Y03271D01*
X03373D02*
X03374Y03273D01*
X03367Y03271D02*
X03373D01*
X02591Y03186D02*
X02591D01*
X02577Y032D02*
X02591Y03186D01*
X02454Y032D02*
X02577D01*
X02598Y03293D02*
X03252D01*
X0259Y03288D02*
X02593D01*
X02598Y03293*
X03252D02*
X03263Y03303D01*
X00996Y02256D02*
X01732D01*
X01739Y02249*
X02499Y02236D02*
X02499Y02236D01*
X02472Y02249D02*
X02494Y0227D01*
X01739Y02249D02*
X02472D01*
X00997Y02236D02*
X02499D01*
X01187Y02314D02*
X02409D01*
X0102Y02481D02*
X01187Y02314D01*
X0181Y01316D02*
X02013D01*
X02016Y01319*
X02004Y01336D02*
X03379D01*
X02028Y01361D02*
X02029Y01361D01*
X02016Y01319D02*
X02499D01*
X02494Y0227D02*
X02529D01*
X02549Y0225D02*
X02608D01*
X02529Y0227D02*
X02549Y0225D01*
X02608D02*
X02629Y02272D01*
X02418Y03118D02*
X02428D01*
X02416Y03199D02*
X02429Y03212D01*
X02438*
X0246Y03235*
X02414Y03199D02*
X02416D01*
X0246Y03172D02*
X02462D01*
X02428Y03118D02*
X02577Y02969D01*
X01904Y04017D02*
X02353D01*
X01903Y04018D02*
X01904Y04017D01*
X02002Y04152D02*
X02043D01*
X01965Y04156D02*
X02018Y04209D01*
X02067D02*
X02121Y04156D01*
X02018Y04209D02*
X02067D01*
X02121Y04156D02*
X0397D01*
X0401Y04115*
X01779Y04156D02*
X01965D01*
X02693Y03266D02*
X027Y03273D01*
X02411Y03266D02*
X02693D01*
X02974Y03257D02*
X02997Y03235D01*
X02428Y03174D02*
X02454Y032D01*
X02429Y02621D02*
X02958D01*
X027Y03273D02*
X03374D01*
X01605Y04136D02*
X01986D01*
X01569Y04171D02*
X01605Y04136D01*
X01986D02*
X02002Y04152D01*
X01769Y00807D02*
X01868Y00906D01*
X01395Y00807D02*
X01769D01*
X01296Y00906D02*
X01395Y00807D01*
X01868Y00906D02*
X02452D01*
X01004D02*
X01296D01*
X03958Y01512D02*
X03989Y01543D01*
Y01543*
X03994Y01548*
Y01551*
X03897Y01512D02*
X03958D01*
X03963Y01552D02*
X03969D01*
X03951Y01564D02*
X03963Y01552D01*
X0393Y01564D02*
X03951D01*
X02694Y01481D02*
X03543D01*
X03584Y0144*
X03993*
X04064Y01511*
X02384Y01941D02*
X03332D01*
X03357Y01916*
X03569*
X03588Y01897*
X03747*
X03804Y0184*
X0505Y03266D02*
X06334D01*
X02499Y02236D02*
X05634D01*
X02629Y0177D02*
X02633Y01766D01*
X02626Y0177D02*
X02629D01*
X02633Y01766D02*
X03475D01*
X03493Y01784*
X03703*
X03709Y0179*
X03993*
X03999Y01796*
X04064*
X06296Y03115D02*
X06302Y03121D01*
X06304*
X04114Y02661D02*
X0418Y02595D01*
X04132Y01751D02*
X04134D01*
X04116Y01735D02*
X04132Y01751D01*
X03579Y01735D02*
X04116D01*
X03578Y01734D02*
X03579Y01735D01*
X02604Y01734D02*
X03578D01*
X02299Y01916D02*
X03334D01*
X0335Y019*
X03444*
X03453Y01891*
X03554*
X02509Y02681D02*
X04212D01*
X04298Y02595*
X02646Y01779D02*
X03465D01*
X03486Y018*
X03635*
X03651Y01816*
X03944*
X03499Y01766D02*
X03719D01*
X03483Y0175D02*
X03499Y01766D01*
X02617Y0175D02*
X03483D01*
X02612Y01755D02*
X02617Y0175D01*
X02549Y01755D02*
X02612D01*
X02423Y03557D02*
X02434Y03546D01*
X0144Y03557D02*
X02423D01*
X03604Y02606D02*
X03623Y02587D01*
X03571Y02606D02*
X03604D01*
X03566Y02601D02*
X03571Y02606D01*
X02821Y02601D02*
X03566D01*
X03419Y01693D02*
X03436Y01711D01*
X03205Y01694D02*
X03312D01*
X03312Y01693*
X03419*
X03307Y0168D02*
X03429D01*
X03306Y01681D02*
X03307Y0168D01*
X03211Y01681D02*
X03306D01*
X03436Y01711D02*
X03589D01*
X03082Y01591D02*
X03091Y016D01*
X03699D02*
X03705Y01606D01*
X03091Y016D02*
X03699D01*
X02478Y00932D02*
Y00937D01*
X02452Y00906D02*
X02478Y00932D01*
X02719Y01591D02*
X03082D01*
X02919Y01536D02*
X03873D01*
X03897Y01512*
X0406Y03155D02*
X06333D01*
X02702Y03257D02*
X02974D01*
X0246Y03235D02*
X0268D01*
X02702Y03257*
X02411Y03174D02*
X02428D01*
X01008Y0143D02*
X0101D01*
X02274Y01506D02*
X03544D01*
X01017Y01437D02*
X02446D01*
X0101Y0143D02*
X01017Y01437D01*
X02059Y01386D02*
X03379D01*
X03402Y01361D02*
X03404Y01363D01*
X02029Y01361D02*
X03402D01*
X02499Y01319D02*
X02502Y01316D01*
X02525Y02463D02*
X02598D01*
X02616Y02481*
X02803Y02307D02*
X02837Y02341D01*
X03498*
X01009Y01956D02*
X0102Y01967D01*
X02409*
X02643Y01616D02*
X03469D01*
X02557Y03616D02*
X02799D01*
X02129Y03587D02*
X02257D01*
X023Y03629*
X02543*
X02557Y03616*
X02123Y03571D02*
X02611D01*
X02636Y03596*
X01754Y03661D02*
X01755Y03661D01*
X02679*
X02679Y03661*
X01549Y03621D02*
X0187D01*
X01895Y03645*
X02652*
X02115Y03601D02*
X02129Y03587D01*
X01593Y03577D02*
X02117D01*
X02652Y03645D02*
X02661Y03636D01*
X03424*
X01884Y03601D02*
X02115D01*
X02117Y03577D02*
X02123Y03571D01*
X02636Y03596D02*
X03239D01*
X01574D02*
X01593Y03577D01*
X02993Y03751D02*
X03699D01*
X03019Y03836D02*
X03699D01*
X03014Y03831D02*
X03019Y03836D01*
X03014Y03831D02*
Y03831D01*
X02894Y01561D02*
X03327D01*
X03336Y01552D02*
X03769D01*
X03327Y01561D02*
X03336Y01552D01*
X03769D02*
X03807Y0159D01*
X03904D02*
X0393Y01564D01*
X03807Y0159D02*
X03904D01*
X03959Y01599D02*
X04178D01*
X03952Y01606D02*
X03959Y01599D01*
X03705Y01606D02*
X03952D01*
X03544Y01506D02*
X03594Y01456D01*
X03922*
X03939Y01473*
X03961D02*
X04034Y01546D01*
X03939Y01473D02*
X03961D01*
X04178Y01599D02*
X04179Y01601D01*
X03469Y01616D02*
X03477Y01623D01*
X04151*
X03792Y01651D02*
X04134D01*
X0401Y04115D02*
X04754D01*
X03829Y03176D02*
X06274D01*
X06275Y03175*
X06377Y03191D02*
X06439D01*
X06361Y03175D02*
X06377Y03191D01*
X06275Y03175D02*
X06361D01*
X06433Y03296D02*
X06438Y03291D01*
X06444*
G54D162*
X01849Y03701D02*
X06294D01*
X01909Y04284D02*
X01941Y04316D01*
X01496Y04204D02*
X01576Y04284D01*
X01909*
X02152Y04316D02*
X02186Y04283D01*
X01941Y04316D02*
X02152D01*
X02186Y04283D02*
X0257D01*
X01413Y04204D02*
X01496D01*
X01362Y04256D02*
X01413Y04204D01*
X01294Y04256D02*
X01362D01*
G54D172*
X04298Y02595D03*
X0418D03*
G54D177*
X02043Y04157D03*
G54D181*
X02645Y0227D03*
X03414Y02892D03*
X04385Y03661D03*
X03657Y03296D03*
X03747Y01679D03*
X04438Y03354D03*
X03542Y03318D03*
X03437Y03476D03*
X03342Y02263D03*
X01015Y01705D03*
X01003Y01177D03*
X01893Y01685D03*
X03799Y03201D03*
X02414Y03199D03*
X02591Y03186D03*
X02462Y03172D03*
X0259Y03288D03*
X02418Y03118D03*
X0522Y04086D03*
X06335Y03147D03*
X06262Y0322D03*
X06287Y03195D03*
X02948Y02456D03*
X03379Y01386D03*
X02803Y02307D03*
X02575Y02412D03*
X02958Y02621D03*
X03404Y01363D03*
X02841Y02263D03*
X02767Y00976D03*
X0274D03*
X02826Y00795D03*
X02821Y02601D03*
X02494Y02696D03*
X01822Y01674D03*
X03804Y0184D03*
X01879Y01811D03*
X03554Y01891D03*
X01567Y01285D03*
X02394Y0272D03*
X02692Y00795D03*
X02409Y02314D03*
X02494Y02661D03*
X03407Y01411D03*
X02499Y02236D03*
X02649Y00976D03*
X02622D03*
X01798Y01304D03*
X02665Y00795D03*
X02799D03*
X03719Y01766D03*
X03379Y01336D03*
X0233Y02215D03*
X0261Y00279D03*
X02578D03*
X02748Y00282D03*
X02905Y00279D03*
X02779Y00279D03*
X02937D03*
X02413D03*
X02444D03*
X01393Y01816D03*
X04794Y02808D03*
X03183Y03135D03*
X03277Y02963D03*
X03197Y0297D03*
X03188Y03187D03*
X0323Y03235D03*
X03358Y03448D03*
X03275Y03141D03*
X03056Y01811D03*
X02434Y03546D03*
X00996Y02256D03*
X02004Y01336D03*
X02028Y01361D03*
X02549Y01755D03*
X01408Y0398D03*
X02353Y04017D03*
X04039Y02406D03*
X04134Y01651D03*
X03994Y01551D03*
X04134Y01751D03*
X04151Y01623D03*
X03969Y01552D03*
X03944Y01816D03*
X04179Y01601D03*
X04034Y01546D03*
X04064Y01796D03*
Y01511D03*
X03263Y03303D03*
X01569Y04171D03*
X05577Y02214D03*
X02694Y01481D03*
X02384Y01941D03*
X06334Y03266D03*
X03744Y03261D03*
X05634Y02236D03*
X02626Y0177D03*
X06304Y03121D03*
X03939D03*
X02604Y01734D03*
X02299Y01916D03*
X02579Y0179D03*
X02259Y03261D03*
X03374Y03273D03*
X03806Y03235D03*
X0257Y04283D03*
X01459Y03147D03*
X0144Y03557D03*
X01903Y04018D03*
X03623Y02587D03*
X03491Y03297D03*
X03394Y03447D03*
X02799Y03616D03*
X03589Y01711D03*
X02478Y00937D03*
X02206Y01298D03*
X02205Y032D03*
X02502Y01316D03*
X02525Y02463D03*
X03498Y02341D03*
X02429Y02621D03*
X01004Y00906D03*
X02446Y01437D03*
X01008Y0143D03*
X02409Y01967D03*
X01009Y01956D03*
X0102Y02481D03*
X02643Y01616D03*
X02666Y0164D03*
X01884Y03601D03*
X01754Y03661D03*
X03424Y03636D03*
X01549Y03621D03*
X03239Y03596D03*
X01574D03*
X02083Y01411D03*
X02059Y01386D03*
X01294Y04256D03*
X02679Y03661D03*
X02993Y03751D03*
X03699D03*
X03014Y03831D03*
X03699Y03836D03*
X02894Y01561D03*
X02919Y01536D03*
X02274Y01506D03*
X02719Y01591D03*
X04754Y04115D03*
X01779Y04156D03*
X03504Y04086D03*
X03854Y03151D03*
X03829Y03176D03*
X06439Y03191D03*
X06354Y03331D03*
X06444Y03291D03*
X03302Y03344D03*
X06409Y03371D03*
X06447Y03396D03*
X06479Y03426D03*
X06509Y03456D03*
X03469D03*
X01849Y03701D03*
X06294D03*
M02*